(kicad_pcb
	(version 20260206)
	(generator "pcbnew")
	(generator_version "10.0")
	(general
		(thickness 1.6)
		(legacy_teardrops no)
	)
	(paper "A4")
	(title_block
		(title "04192023_DAF0TMB3IC0_F0TG_MB_C_brd_V02_OCP.brd")
		(comment 1 "Grand Teton / footprints 6252-6258 of 8354")
	)
	(layers
		(0 "F.Cu" signal "TOP")
		(4 "In1.Cu" signal "GND")
		(6 "In2.Cu" signal "IN1")
		(8 "In3.Cu" signal "GND1")
		(10 "In4.Cu" signal "IN2")
		(12 "In5.Cu" signal "GND2")
		(14 "In6.Cu" signal "IN3")
		(16 "In7.Cu" signal "GND3")
		(18 "In8.Cu" signal "VCC")
		(20 "In9.Cu" signal "VCC1")
		(22 "In10.Cu" signal "GND4")
		(24 "In11.Cu" signal "IN4")
		(26 "In12.Cu" signal "GND5")
		(28 "In13.Cu" signal "IN5")
		(30 "In14.Cu" signal "GND6")
		(32 "In15.Cu" signal "IN6")
		(34 "In16.Cu" signal "GND7")
		(2 "B.Cu" signal "BOTTOM")
		(9 "F.Adhes" user "F.Adhesive")
		(11 "B.Adhes" user "B.Adhesive")
		(13 "F.Paste" user "Package Geometry/Pastemask Top")
		(15 "B.Paste" user "Package Geometry/Pastemask Bottom")
		(5 "F.SilkS" user "Ref Des/Silkscreen Top")
		(7 "B.SilkS" user "Ref Des/Silkscreen Bottom")
		(1 "F.Mask" user "Board Geometry/Soldermask Top")
		(3 "B.Mask" user "Board Geometry/Soldermask Bottom")
		(17 "Dwgs.User" user "User.Drawings")
		(19 "Cmts.User" user "User.Comments")
		(21 "Eco1.User" user "User.Eco1")
		(23 "Eco2.User" user "User.Eco2")
		(25 "Edge.Cuts" user "Board Geometry/Outline")
		(27 "Margin" user)
		(31 "F.CrtYd" user "Package Geometry/Place Bound Top")
		(29 "B.CrtYd" user "Package Geometry/Place Bound Bottom")
		(35 "F.Fab" user "Ref Des/Assembly Top")
		(33 "B.Fab" user "Ref Des/Assembly Bottom")
	)
	(footprint ""
		(layer "B.Cu")
		(at 119.293386 -253.432564)
		(property "Reference" "C2280"
			(at 0 0 0)
			(layer "B.SilkS")
			(hide yes)
			(effects
				(font
					(size 1.27 1.27)
				)
				(justify mirror)
			)
		)
		(property "Value" ""
			(at 0 0 0)
			(layer "B.Fab")
			(effects
				(font
					(size 1.27 1.27)
				)
				(justify mirror)
			)
		)
		(duplicate_pad_numbers_are_jumpers no)
		(fp_line
			(start -0.7874 -0.4064)
			(end -0.7874 0.4064)
			(stroke
				(width 0.1524)
				(type default)
			)
			(layer "B.SilkS")
		)
		(fp_line
			(start -0.7874 0.4064)
			(end 0.7874 0.4064)
			(stroke
				(width 0.1524)
				(type default)
			)
			(layer "B.SilkS")
		)
		(fp_line
			(start 0.7874 -0.4064)
			(end -0.7874 -0.4064)
			(stroke
				(width 0.1524)
				(type default)
			)
			(layer "B.SilkS")
		)
		(fp_line
			(start 0.7874 0.4064)
			(end 0.7874 -0.4064)
			(stroke
				(width 0.1524)
				(type default)
			)
			(layer "B.SilkS")
		)
		(fp_line
			(start -0.67945 -0.3048)
			(end -0.67945 0.3048)
			(stroke
				(width 0.1)
				(type default)
			)
			(layer "B.Fab")
		)
		(fp_line
			(start -0.67945 0.3048)
			(end -0.120396 0.3048)
			(stroke
				(width 0.1)
				(type default)
			)
			(layer "B.Fab")
		)
		(fp_line
			(start -0.12065 -0.3048)
			(end -0.67945 -0.3048)
			(stroke
				(width 0.1)
				(type default)
			)
			(layer "B.Fab")
		)
		(fp_line
			(start -0.12065 -0.2794)
			(end -0.12065 -0.3048)
			(stroke
				(width 0.1)
				(type default)
			)
			(layer "B.Fab")
		)
		(fp_line
			(start -0.120396 0.2794)
			(end 0.12065 0.2794)
			(stroke
				(width 0.1)
				(type default)
			)
			(layer "B.Fab")
		)
		(fp_line
			(start -0.120396 0.3048)
			(end -0.120396 0.2794)
			(stroke
				(width 0.1)
				(type default)
			)
			(layer "B.Fab")
		)
		(fp_line
			(start 0.12065 -0.305054)
			(end 0.12065 -0.2794)
			(stroke
				(width 0.1)
				(type default)
			)
			(layer "B.Fab")
		)
		(fp_line
			(start 0.12065 -0.2794)
			(end -0.12065 -0.2794)
			(stroke
				(width 0.1)
				(type default)
			)
			(layer "B.Fab")
		)
		(fp_line
			(start 0.12065 0.2794)
			(end 0.12065 0.3048)
			(stroke
				(width 0.1)
				(type default)
			)
			(layer "B.Fab")
		)
		(fp_line
			(start 0.12065 0.3048)
			(end 0.67945 0.3048)
			(stroke
				(width 0.1)
				(type default)
			)
			(layer "B.Fab")
		)
		(fp_line
			(start 0.67945 -0.305054)
			(end 0.12065 -0.305054)
			(stroke
				(width 0.1)
				(type default)
			)
			(layer "B.Fab")
		)
		(fp_line
			(start 0.67945 0.3048)
			(end 0.67945 -0.305054)
			(stroke
				(width 0.1)
				(type default)
			)
			(layer "B.Fab")
		)
		(pad "1" smd circle
			(at 0.40005 0 180)
			(size 0 0)
			(layers "B.Cu" "B.Mask" "B.Paste")
			(net "PVDDCR_SOC_P1")
		)
		(pad "2" smd circle
			(at -0.40005 0 180)
			(size 0 0)
			(layers "B.Cu" "B.Mask" "B.Paste")
			(net "GND")
		)
	)
	(footprint ""
		(layer "B.Cu")
		(at 185.458608 -118.242842 90)
		(property "Reference" "C1134"
			(at 0 0 90)
			(layer "B.SilkS")
			(hide yes)
			(effects
				(font
					(size 1.27 1.27)
				)
				(justify mirror)
			)
		)
		(property "Value" ""
			(at 0 0 90)
			(layer "B.Fab")
			(effects
				(font
					(size 1.27 1.27)
				)
				(justify mirror)
			)
		)
		(duplicate_pad_numbers_are_jumpers no)
		(fp_line
			(start 0.69215 -0.2921)
			(end -0.69215 -0.2921)
			(stroke
				(width 0.1524)
				(type default)
			)
			(layer "B.SilkS")
		)
		(fp_line
			(start -0.69215 -0.2921)
			(end -0.69215 0.2921)
			(stroke
				(width 0.1524)
				(type default)
			)
			(layer "B.SilkS")
		)
		(fp_line
			(start 0.69215 0.2921)
			(end 0.69215 -0.2921)
			(stroke
				(width 0.1524)
				(type default)
			)
			(layer "B.SilkS")
		)
		(fp_line
			(start -0.69215 0.2921)
			(end 0.69215 0.2921)
			(stroke
				(width 0.1524)
				(type default)
			)
			(layer "B.SilkS")
		)
		(fp_line
			(start 0.51435 -0.2794)
			(end -0.51435 -0.2794)
			(stroke
				(width 0.1)
				(type default)
			)
			(layer "B.Fab")
		)
		(fp_line
			(start -0.51435 -0.2794)
			(end -0.51435 0.2794)
			(stroke
				(width 0.1)
				(type default)
			)
			(layer "B.Fab")
		)
		(fp_line
			(start 0.51435 0.2794)
			(end 0.51435 -0.2794)
			(stroke
				(width 0.1)
				(type default)
			)
			(layer "B.Fab")
		)
		(fp_line
			(start -0.51435 0.2794)
			(end 0.51435 0.2794)
			(stroke
				(width 0.1)
				(type default)
			)
			(layer "B.Fab")
		)
		(pad "1" smd circle
			(at 0.40005 0 270)
			(size 0 0)
			(layers "B.Cu" "B.Mask" "B.Paste")
			(net "P1V8_AUX")
		)
		(pad "2" smd circle
			(at -0.40005 0 270)
			(size 0 0)
			(layers "B.Cu" "B.Mask" "B.Paste")
			(net "GND")
		)
		(zone
			(layer "B.Cu")
			(hatch none 0.5)
			(connect_pads
				(clearance 0)
			)
			(min_thickness 0.25)
			(keepout
				(tracks not_allowed)
				(vias allowed)
				(pads allowed)
				(copperpour not_allowed)
				(footprints allowed)
			)
			(placement
				(enabled no)
				(sheetname "")
			)
			(fill
				(thermal_gap 0.5)
				(thermal_bridge_width 0.5)
				(island_removal_mode 0)
			)
			(polygon
				(pts
					(xy 185.312558 -118.142512) (xy 185.312558 -118.341902) (xy 185.370724 -118.433342) (xy 185.546238 -118.433342)
					(xy 185.604404 -118.341902) (xy 185.604404 -118.142512) (xy 185.546238 -118.052342) (xy 185.370978 -118.052342)
				)
			)
		)
	)
	(footprint ""
		(layer "B.Cu")
		(at 99.916234 -245.868952 -90)
		(property "Reference" "C2295"
			(at 0 0 90)
			(layer "B.SilkS")
			(hide yes)
			(effects
				(font
					(size 1.27 1.27)
				)
				(justify mirror)
			)
		)
		(property "Value" ""
			(at 0 0 90)
			(layer "B.Fab")
			(effects
				(font
					(size 1.27 1.27)
				)
				(justify mirror)
			)
		)
		(duplicate_pad_numbers_are_jumpers no)
		(fp_line
			(start -0.7874 0.4064)
			(end 0.7874 0.4064)
			(stroke
				(width 0.1524)
				(type default)
			)
			(layer "B.SilkS")
		)
		(fp_line
			(start 0.7874 0.4064)
			(end 0.7874 -0.4064)
			(stroke
				(width 0.1524)
				(type default)
			)
			(layer "B.SilkS")
		)
		(fp_line
			(start -0.7874 -0.4064)
			(end -0.7874 0.4064)
			(stroke
				(width 0.1524)
				(type default)
			)
			(layer "B.SilkS")
		)
		(fp_line
			(start 0.7874 -0.4064)
			(end -0.7874 -0.4064)
			(stroke
				(width 0.1524)
				(type default)
			)
			(layer "B.SilkS")
		)
		(fp_line
			(start -0.67945 0.3048)
			(end -0.120396 0.3048)
			(stroke
				(width 0.1)
				(type default)
			)
			(layer "B.Fab")
		)
		(fp_line
			(start -0.120396 0.3048)
			(end -0.120396 0.2794)
			(stroke
				(width 0.1)
				(type default)
			)
			(layer "B.Fab")
		)
		(fp_line
			(start 0.12065 0.3048)
			(end 0.67945 0.3048)
			(stroke
				(width 0.1)
				(type default)
			)
			(layer "B.Fab")
		)
		(fp_line
			(start 0.67945 0.3048)
			(end 0.67945 -0.305054)
			(stroke
				(width 0.1)
				(type default)
			)
			(layer "B.Fab")
		)
		(fp_line
			(start -0.120396 0.2794)
			(end 0.12065 0.2794)
			(stroke
				(width 0.1)
				(type default)
			)
			(layer "B.Fab")
		)
		(fp_line
			(start 0.12065 0.2794)
			(end 0.12065 0.3048)
			(stroke
				(width 0.1)
				(type default)
			)
			(layer "B.Fab")
		)
		(fp_line
			(start -0.12065 -0.2794)
			(end -0.12065 -0.3048)
			(stroke
				(width 0.1)
				(type default)
			)
			(layer "B.Fab")
		)
		(fp_line
			(start 0.12065 -0.2794)
			(end -0.12065 -0.2794)
			(stroke
				(width 0.1)
				(type default)
			)
			(layer "B.Fab")
		)
		(fp_line
			(start -0.67945 -0.3048)
			(end -0.67945 0.3048)
			(stroke
				(width 0.1)
				(type default)
			)
			(layer "B.Fab")
		)
		(fp_line
			(start -0.12065 -0.3048)
			(end -0.67945 -0.3048)
			(stroke
				(width 0.1)
				(type default)
			)
			(layer "B.Fab")
		)
		(fp_line
			(start 0.12065 -0.305054)
			(end 0.12065 -0.2794)
			(stroke
				(width 0.1)
				(type default)
			)
			(layer "B.Fab")
		)
		(fp_line
			(start 0.67945 -0.305054)
			(end 0.12065 -0.305054)
			(stroke
				(width 0.1)
				(type default)
			)
			(layer "B.Fab")
		)
		(pad "1" smd circle
			(at 0.40005 0 90)
			(size 0 0)
			(layers "B.Cu" "B.Mask" "B.Paste")
			(net "PVDDCR_CPU0_P1")
		)
		(pad "2" smd circle
			(at -0.40005 0 90)
			(size 0 0)
			(layers "B.Cu" "B.Mask" "B.Paste")
			(net "GND")
		)
	)
	(footprint ""
		(layer "B.Cu")
		(at 367.233454 -251.78131)
		(property "Reference" "C3896"
			(at 0 0 0)
			(layer "B.SilkS")
			(hide yes)
			(effects
				(font
					(size 1.27 1.27)
				)
				(justify mirror)
			)
		)
		(property "Value" ""
			(at 0 0 0)
			(layer "B.Fab")
			(effects
				(font
					(size 1.27 1.27)
				)
				(justify mirror)
			)
		)
		(duplicate_pad_numbers_are_jumpers no)
		(fp_line
			(start -0.7874 -0.4064)
			(end -0.7874 0.4064)
			(stroke
				(width 0.1524)
				(type default)
			)
			(layer "B.SilkS")
		)
		(fp_line
			(start -0.7874 0.4064)
			(end 0.7874 0.4064)
			(stroke
				(width 0.1524)
				(type default)
			)
			(layer "B.SilkS")
		)
		(fp_line
			(start 0.7874 -0.4064)
			(end -0.7874 -0.4064)
			(stroke
				(width 0.1524)
				(type default)
			)
			(layer "B.SilkS")
		)
		(fp_line
			(start 0.7874 0.4064)
			(end 0.7874 -0.4064)
			(stroke
				(width 0.1524)
				(type default)
			)
			(layer "B.SilkS")
		)
		(fp_line
			(start -0.67945 -0.3048)
			(end -0.67945 0.3048)
			(stroke
				(width 0.1)
				(type default)
			)
			(layer "B.Fab")
		)
		(fp_line
			(start -0.67945 0.3048)
			(end -0.120396 0.3048)
			(stroke
				(width 0.1)
				(type default)
			)
			(layer "B.Fab")
		)
		(fp_line
			(start -0.12065 -0.3048)
			(end -0.67945 -0.3048)
			(stroke
				(width 0.1)
				(type default)
			)
			(layer "B.Fab")
		)
		(fp_line
			(start -0.12065 -0.2794)
			(end -0.12065 -0.3048)
			(stroke
				(width 0.1)
				(type default)
			)
			(layer "B.Fab")
		)
		(fp_line
			(start -0.120396 0.2794)
			(end 0.12065 0.2794)
			(stroke
				(width 0.1)
				(type default)
			)
			(layer "B.Fab")
		)
		(fp_line
			(start -0.120396 0.3048)
			(end -0.120396 0.2794)
			(stroke
				(width 0.1)
				(type default)
			)
			(layer "B.Fab")
		)
		(fp_line
			(start 0.12065 -0.305054)
			(end 0.12065 -0.2794)
			(stroke
				(width 0.1)
				(type default)
			)
			(layer "B.Fab")
		)
		(fp_line
			(start 0.12065 -0.2794)
			(end -0.12065 -0.2794)
			(stroke
				(width 0.1)
				(type default)
			)
			(layer "B.Fab")
		)
		(fp_line
			(start 0.12065 0.2794)
			(end 0.12065 0.3048)
			(stroke
				(width 0.1)
				(type default)
			)
			(layer "B.Fab")
		)
		(fp_line
			(start 0.12065 0.3048)
			(end 0.67945 0.3048)
			(stroke
				(width 0.1)
				(type default)
			)
			(layer "B.Fab")
		)
		(fp_line
			(start 0.67945 -0.305054)
			(end 0.12065 -0.305054)
			(stroke
				(width 0.1)
				(type default)
			)
			(layer "B.Fab")
		)
		(fp_line
			(start 0.67945 0.3048)
			(end 0.67945 -0.305054)
			(stroke
				(width 0.1)
				(type default)
			)
			(layer "B.Fab")
		)
		(pad "1" smd circle
			(at 0.40005 0 180)
			(size 0 0)
			(layers "B.Cu" "B.Mask" "B.Paste")
			(net "PVDDCR_SOC_P0")
		)
		(pad "2" smd circle
			(at -0.40005 0 180)
			(size 0 0)
			(layers "B.Cu" "B.Mask" "B.Paste")
			(net "GND")
		)
	)
	(footprint ""
		(layer "B.Cu")
		(at 191.271144 -79.05623 -90)
		(property "Reference" "R1290"
			(at 0 0 90)
			(layer "B.SilkS")
			(hide yes)
			(effects
				(font
					(size 1.27 1.27)
				)
				(justify mirror)
			)
		)
		(property "Value" ""
			(at 0 0 90)
			(layer "B.Fab")
			(effects
				(font
					(size 1.27 1.27)
				)
				(justify mirror)
			)
		)
		(duplicate_pad_numbers_are_jumpers no)
		(fp_line
			(start -0.7874 0.4064)
			(end 0.7874 0.4064)
			(stroke
				(width 0.1524)
				(type default)
			)
			(layer "B.SilkS")
		)
		(fp_line
			(start 0.7874 0.4064)
			(end 0.7874 -0.4064)
			(stroke
				(width 0.1524)
				(type default)
			)
			(layer "B.SilkS")
		)
		(fp_line
			(start -0.7874 -0.4064)
			(end -0.7874 0.4064)
			(stroke
				(width 0.1524)
				(type default)
			)
			(layer "B.SilkS")
		)
		(fp_line
			(start 0.7874 -0.4064)
			(end -0.7874 -0.4064)
			(stroke
				(width 0.1524)
				(type default)
			)
			(layer "B.SilkS")
		)
		(fp_line
			(start -0.67945 0.3048)
			(end -0.120396 0.3048)
			(stroke
				(width 0.1)
				(type default)
			)
			(layer "B.Fab")
		)
		(fp_line
			(start -0.120396 0.3048)
			(end -0.120396 0.2794)
			(stroke
				(width 0.1)
				(type default)
			)
			(layer "B.Fab")
		)
		(fp_line
			(start 0.12065 0.3048)
			(end 0.67945 0.3048)
			(stroke
				(width 0.1)
				(type default)
			)
			(layer "B.Fab")
		)
		(fp_line
			(start 0.67945 0.3048)
			(end 0.67945 -0.305054)
			(stroke
				(width 0.1)
				(type default)
			)
			(layer "B.Fab")
		)
		(fp_line
			(start -0.120396 0.2794)
			(end 0.12065 0.2794)
			(stroke
				(width 0.1)
				(type default)
			)
			(layer "B.Fab")
		)
		(fp_line
			(start 0.12065 0.2794)
			(end 0.12065 0.3048)
			(stroke
				(width 0.1)
				(type default)
			)
			(layer "B.Fab")
		)
		(fp_line
			(start -0.12065 -0.2794)
			(end -0.12065 -0.3048)
			(stroke
				(width 0.1)
				(type default)
			)
			(layer "B.Fab")
		)
		(fp_line
			(start 0.12065 -0.2794)
			(end -0.12065 -0.2794)
			(stroke
				(width 0.1)
				(type default)
			)
			(layer "B.Fab")
		)
		(fp_line
			(start -0.67945 -0.3048)
			(end -0.67945 0.3048)
			(stroke
				(width 0.1)
				(type default)
			)
			(layer "B.Fab")
		)
		(fp_line
			(start -0.12065 -0.3048)
			(end -0.67945 -0.3048)
			(stroke
				(width 0.1)
				(type default)
			)
			(layer "B.Fab")
		)
		(fp_line
			(start 0.12065 -0.305054)
			(end 0.12065 -0.2794)
			(stroke
				(width 0.1)
				(type default)
			)
			(layer "B.Fab")
		)
		(fp_line
			(start 0.67945 -0.305054)
			(end 0.12065 -0.305054)
			(stroke
				(width 0.1)
				(type default)
			)
			(layer "B.Fab")
		)
		(pad "1" smd circle
			(at 0.40005 0 90)
			(size 0 0)
			(layers "B.Cu" "B.Mask" "B.Paste")
			(net "OCP_SFF_RBT_ARB_IN_R")
		)
		(pad "2" smd circle
			(at -0.40005 0 90)
			(size 0 0)
			(layers "B.Cu" "B.Mask" "B.Paste")
			(net "OCP_SFF_RBT_ARB_IN")
		)
	)
	(footprint ""
		(layer "B.Cu")
		(at 215.0618 -341.884)
		(property "Reference" "R872"
			(at 0 0 0)
			(layer "B.SilkS")
			(hide yes)
			(effects
				(font
					(size 1.27 1.27)
				)
				(justify mirror)
			)
		)
		(property "Value" ""
			(at 0 0 0)
			(layer "B.Fab")
			(effects
				(font
					(size 1.27 1.27)
				)
				(justify mirror)
			)
		)
		(duplicate_pad_numbers_are_jumpers no)
		(fp_line
			(start -0.32512 -0.175006)
			(end -0.32512 0.175006)
			(stroke
				(width 0.1)
				(type default)
			)
			(layer "B.Fab")
		)
		(fp_line
			(start -0.32512 0.175006)
			(end 0.32512 0.175006)
			(stroke
				(width 0.1)
				(type default)
			)
			(layer "B.Fab")
		)
		(fp_line
			(start 0.32512 -0.175006)
			(end -0.32512 -0.175006)
			(stroke
				(width 0.1)
				(type default)
			)
			(layer "B.Fab")
		)
		(fp_line
			(start 0.32512 0.175006)
			(end 0.32512 -0.175006)
			(stroke
				(width 0.1)
				(type default)
			)
			(layer "B.Fab")
		)
		(pad "1" smd rect
			(at 0.2667 0 180)
			(size 0.3048 0.381)
			(layers "B.Cu" "B.Mask" "B.Paste")
			(net "SMB_RT_CPU1_P2_R_SCL")
		)
		(pad "2" smd rect
			(at -0.2667 0)
			(size 0.3048 0.381)
			(layers "B.Cu" "B.Mask" "B.Paste")
			(net "SMB_RT_CPU1_P2_R2_SCL")
		)
	)
	(footprint ""
		(layer "B.Cu")
		(at 311.791096 -398.942052 90)
		(property "Reference" "C510"
			(at 0 0 90)
			(layer "B.SilkS")
			(hide yes)
			(effects
				(font
					(size 1.27 1.27)
				)
				(justify mirror)
			)
		)
		(property "Value" ""
			(at 0 0 90)
			(layer "B.Fab")
			(effects
				(font
					(size 1.27 1.27)
				)
				(justify mirror)
			)
		)
		(duplicate_pad_numbers_are_jumpers no)
		(fp_line
			(start 0.7874 -0.4064)
			(end -0.7874 -0.4064)
			(stroke
				(width 0.1524)
				(type default)
			)
			(layer "B.SilkS")
		)
		(fp_line
			(start -0.7874 -0.4064)
			(end -0.7874 0.4064)
			(stroke
				(width 0.1524)
				(type default)
			)
			(layer "B.SilkS")
		)
		(fp_line
			(start 0.7874 0.4064)
			(end 0.7874 -0.4064)
			(stroke
				(width 0.1524)
				(type default)
			)
			(layer "B.SilkS")
		)
		(fp_line
			(start -0.7874 0.4064)
			(end 0.7874 0.4064)
			(stroke
				(width 0.1524)
				(type default)
			)
			(layer "B.SilkS")
		)
		(fp_line
			(start 0.67945 -0.305054)
			(end 0.12065 -0.305054)
			(stroke
				(width 0.1)
				(type default)
			)
			(layer "B.Fab")
		)
		(fp_line
			(start 0.12065 -0.305054)
			(end 0.12065 -0.2794)
			(stroke
				(width 0.1)
				(type default)
			)
			(layer "B.Fab")
		)
		(fp_line
			(start -0.12065 -0.3048)
			(end -0.67945 -0.3048)
			(stroke
				(width 0.1)
				(type default)
			)
			(layer "B.Fab")
		)
		(fp_line
			(start -0.67945 -0.3048)
			(end -0.67945 0.3048)
			(stroke
				(width 0.1)
				(type default)
			)
			(layer "B.Fab")
		)
		(fp_line
			(start 0.12065 -0.2794)
			(end -0.12065 -0.2794)
			(stroke
				(width 0.1)
				(type default)
			)
			(layer "B.Fab")
		)
		(fp_line
			(start -0.12065 -0.2794)
			(end -0.12065 -0.3048)
			(stroke
				(width 0.1)
				(type default)
			)
			(layer "B.Fab")
		)
		(fp_line
			(start 0.12065 0.2794)
			(end 0.12065 0.3048)
			(stroke
				(width 0.1)
				(type default)
			)
			(layer "B.Fab")
		)
		(fp_line
			(start -0.120396 0.2794)
			(end 0.12065 0.2794)
			(stroke
				(width 0.1)
				(type default)
			)
			(layer "B.Fab")
		)
		(fp_line
			(start 0.67945 0.3048)
			(end 0.67945 -0.305054)
			(stroke
				(width 0.1)
				(type default)
			)
			(layer "B.Fab")
		)
		(fp_line
			(start 0.12065 0.3048)
			(end 0.67945 0.3048)
			(stroke
				(width 0.1)
				(type default)
			)
			(layer "B.Fab")
		)
		(fp_line
			(start -0.120396 0.3048)
			(end -0.120396 0.2794)
			(stroke
				(width 0.1)
				(type default)
			)
			(layer "B.Fab")
		)
		(fp_line
			(start -0.67945 0.3048)
			(end -0.120396 0.3048)
			(stroke
				(width 0.1)
				(type default)
			)
			(layer "B.Fab")
		)
		(pad "1" smd circle
			(at 0.40005 0 270)
			(size 0 0)
			(layers "B.Cu" "B.Mask" "B.Paste")
			(net "P1V8_CPU0_RT0_1A")
		)
		(pad "2" smd circle
			(at -0.40005 0 270)
			(size 0 0)
			(layers "B.Cu" "B.Mask" "B.Paste")
			(net "GND")
		)
	)
)
